#ISCELL
  pure_quanta quanta_title_block_c *
  *
#ISCELL
  standard tap *
  page21_i10
#ISCELL
  standard tap *
  page21_i100
#ISCELL
  standard tap *
  page21_i101
#ISCELL
  standard tap *
  page21_i102
#ISCELL
  standard tap *
  page21_i103
#ISCELL
  standard tap *
  page21_i104
#ISCELL
  standard tap *
  page21_i105
#ISCELL
  standard tap *
  page21_i106
#ISCELL
  standard tap *
  page21_i107
#ISCELL
  standard tap *
  page21_i108
#ISCELL
  standard tap *
  page21_i109
#ISCELL
  standard tap *
  page21_i11
#ISCELL
  standard tap *
  page21_i110
#ISCELL
  standard tap *
  page21_i111
#ISCELL
  standard tap *
  page21_i112
#ISCELL
  standard tap *
  page21_i113
#ISCELL
  standard tap *
  page21_i114
#ISCELL
  standard offpage *
  page21_i115
#ISCELL
  standard offpage *
  page21_i116
#ISCELL
  standard offpage *
  page21_i117
#ISCELL
  standard offpage *
  page21_i118
#ISCELL
  standard offpage *
  page21_i119
#ISCELL
  standard tap *
  page21_i12
#ISCELL
  standard offpage *
  page21_i120
#ISCELL
  standard offpage *
  page21_i121
#ISCELL
  standard offpage *
  page21_i122
#ISCELL
  standard offpage *
  page21_i123
#ISCELL
  standard offpage *
  page21_i124
#ISCELL
  standard tap *
  page21_i125
#ISCELL
  standard tap *
  page21_i126
#ISCELL
  standard tap *
  page21_i127
#ISCELL
  standard tap *
  page21_i128
#ISCELL
  standard tap *
  page21_i129
#ISCELL
  standard tap *
  page21_i13
#ISCELL
  standard tap *
  page21_i130
#ISCELL
  standard tap *
  page21_i131
#ISCELL
  standard tap *
  page21_i132
#ISCELL
  standard tap *
  page21_i133
#ISCELL
  standard tap *
  page21_i134
#ISCELL
  standard tap *
  page21_i135
#ISCELL
  standard tap *
  page21_i136
#ISCELL
  standard tap *
  page21_i137
#ISCELL
  standard tap *
  page21_i138
#ISCELL
  standard tap *
  page21_i139
#ISCELL
  standard tap *
  page21_i14
#ISCELL
  standard tap *
  page21_i140
#ISCELL
  standard tap *
  page21_i141
#ISCELL
  standard tap *
  page21_i142
#ISCELL
  standard tap *
  page21_i143
#ISCELL
  standard tap *
  page21_i144
#ISCELL
  standard tap *
  page21_i145
#ISCELL
  standard tap *
  page21_i146
#ISCELL
  standard tap *
  page21_i147
#ISCELL
  standard tap *
  page21_i148
#ISCELL
  standard tap *
  page21_i149
#ISCELL
  standard tap *
  page21_i15
#ISCELL
  standard tap *
  page21_i150
#ISCELL
  standard tap *
  page21_i151
#ISCELL
  standard tap *
  page21_i152
#ISCELL
  standard tap *
  page21_i153
#ISCELL
  standard tap *
  page21_i154
#ISCELL
  standard tap *
  page21_i155
#ISCELL
  standard tap *
  page21_i156
#ISCELL
  standard tap *
  page21_i157
#ISCELL
  standard tap *
  page21_i158
#ISCELL
  standard tap *
  page21_i159
#ISCELL
  standard tap *
  page21_i16
#ISCELL
  standard tap *
  page21_i160
#ISCELL
  standard tap *
  page21_i161
#ISCELL
  standard offpage *
  page21_i162
#ISCELL
  standard offpage *
  page21_i163
#ISCELL
  standard offpage *
  page21_i164
#ISCELL
  standard tap *
  page21_i165
#ISCELL
  standard tap *
  page21_i166
#ISCELL
  standard tap *
  page21_i167
#ISCELL
  standard offpage *
  page21_i168
#CELL
  pure_quanta socket4677_azif0045p001c01cs *
  page21_i169
#ISCELL
  standard tap *
  page21_i17
#ISCELL
  standard tap *
  page21_i18
#ISCELL
  standard tap *
  page21_i19
#ISCELL
  standard tap *
  page21_i2
#ISCELL
  standard tap *
  page21_i20
#ISCELL
  standard tap *
  page21_i21
#ISCELL
  standard tap *
  page21_i22
#ISCELL
  standard tap *
  page21_i23
#ISCELL
  standard tap *
  page21_i24
#ISCELL
  standard tap *
  page21_i25
#ISCELL
  standard tap *
  page21_i26
#ISCELL
  standard tap *
  page21_i27
#ISCELL
  standard tap *
  page21_i28
#ISCELL
  standard tap *
  page21_i29
#ISCELL
  standard offpage *
  page21_i3
#ISCELL
  standard tap *
  page21_i30
#ISCELL
  standard tap *
  page21_i31
#ISCELL
  standard tap *
  page21_i32
#ISCELL
  standard tap *
  page21_i33
#ISCELL
  standard tap *
  page21_i34
#ISCELL
  standard tap *
  page21_i35
#ISCELL
  standard tap *
  page21_i36
#ISCELL
  standard tap *
  page21_i37
#ISCELL
  standard tap *
  page21_i38
#ISCELL
  standard tap *
  page21_i39
#ISCELL
  standard offpage *
  page21_i4
#ISCELL
  standard tap *
  page21_i40
#ISCELL
  standard tap *
  page21_i41
#ISCELL
  standard tap *
  page21_i42
#ISCELL
  standard tap *
  page21_i43
#ISCELL
  standard tap *
  page21_i44
#ISCELL
  standard offpage *
  page21_i45
#ISCELL
  standard offpage *
  page21_i46
#ISCELL
  standard tap *
  page21_i47
#ISCELL
  standard tap *
  page21_i48
#ISCELL
  standard tap *
  page21_i49
#ISCELL
  standard offpage *
  page21_i5
#ISCELL
  standard tap *
  page21_i50
#ISCELL
  standard tap *
  page21_i51
#ISCELL
  standard tap *
  page21_i52
#ISCELL
  standard tap *
  page21_i53
#ISCELL
  standard tap *
  page21_i54
#ISCELL
  standard tap *
  page21_i55
#ISCELL
  standard tap *
  page21_i56
#ISCELL
  standard tap *
  page21_i57
#ISCELL
  standard tap *
  page21_i58
#ISCELL
  standard tap *
  page21_i59
#ISCELL
  standard tap *
  page21_i6
#ISCELL
  standard tap *
  page21_i60
#ISCELL
  standard tap *
  page21_i61
#ISCELL
  standard tap *
  page21_i62
#ISCELL
  standard tap *
  page21_i63
#ISCELL
  standard tap *
  page21_i64
#ISCELL
  standard tap *
  page21_i65
#ISCELL
  standard tap *
  page21_i66
#ISCELL
  standard tap *
  page21_i67
#ISCELL
  standard tap *
  page21_i68
#ISCELL
  standard tap *
  page21_i69
#ISCELL
  standard tap *
  page21_i7
#ISCELL
  standard tap *
  page21_i70
#ISCELL
  standard tap *
  page21_i71
#ISCELL
  standard tap *
  page21_i72
#ISCELL
  standard tap *
  page21_i73
#ISCELL
  standard tap *
  page21_i74
#ISCELL
  standard tap *
  page21_i75
#ISCELL
  standard tap *
  page21_i76
#ISCELL
  standard tap *
  page21_i77
#ISCELL
  standard tap *
  page21_i78
#ISCELL
  standard tap *
  page21_i79
#ISCELL
  standard tap *
  page21_i8
#ISCELL
  standard tap *
  page21_i80
#ISCELL
  standard tap *
  page21_i81
#ISCELL
  standard tap *
  page21_i82
#ISCELL
  standard tap *
  page21_i83
#ISCELL
  standard tap *
  page21_i84
#ISCELL
  standard tap *
  page21_i85
#ISCELL
  standard tap *
  page21_i86
#ISCELL
  standard tap *
  page21_i87
#ISCELL
  standard offpage *
  page21_i88
#ISCELL
  standard tap *
  page21_i89
#ISCELL
  standard tap *
  page21_i9
#ISCELL
  standard tap *
  page21_i90
#ISCELL
  standard tap *
  page21_i91
#ISCELL
  standard offpage *
  page21_i92
#ISCELL
  standard tap *
  page21_i93
#ISCELL
  standard tap *
  page21_i94
#ISCELL
  standard tap *
  page21_i95
#ISCELL
  standard tap *
  page21_i96
#ISCELL
  standard tap *
  page21_i97
#ISCELL
  standard tap *
  page21_i98
#ISCELL
  standard tap *
  page21_i99
